# BASEBOARD_FAB2 (Tioga Pass) — schematic netlist excerpt (pin names and nets, part order shuffled) for the footprints in the layout excerpt that follows; sources: Cadence DE-HDL packaged netlist, KiCad conversion of Wiwynn_Tioga_Pass_MB.brd

R7B17  RES  1.00K 1% CHIP  pkg 0402  page 232 : A = P3V3_STBY ; B = PWRGD_PVPP_DEF_R
C6D2  CAP_A  22.0UF 4V 20% X6S  pkg 0603V  page 42 : A = PVCCMCP_CPU0 ; B = GND
R6D16  RES  0.0 5% EMPTY  pkg 0402  page 156 : A = FM_CPU_BMC_INIT ; B = H_CPU0_BMCINIT

(kicad_pcb
	(version 20260206)
	(generator "pcbnew")
	(generator_version "10.0")
	(general
		(thickness 1.6)
		(legacy_teardrops no)
	)
	(paper "A4")
	(title_block
		(title "Wiwynn_Tioga_Pass_MB.brd")
		(comment 1 "Tioga Pass / footprints 1092-1094 of 4770")
	)
	(layers
		(0 "F.Cu" signal "TOP")
		(4 "In1.Cu" signal "L2GND")
		(6 "In2.Cu" signal "L3")
		(8 "In3.Cu" signal "L4GND")
		(10 "In4.Cu" signal "L5")
		(12 "In5.Cu" signal "L6GND")
		(14 "In6.Cu" signal "L7VCC")
		(16 "In7.Cu" signal "L8VCC")
		(18 "In8.Cu" signal "L9GND")
		(20 "In9.Cu" signal "L10")
		(22 "In10.Cu" signal "L11GND")
		(24 "In11.Cu" signal "L12")
		(26 "In12.Cu" signal "L13GND")
		(2 "B.Cu" signal "BOTTOM")
		(9 "F.Adhes" user "F.Adhesive")
		(11 "B.Adhes" user "B.Adhesive")
		(13 "F.Paste" user "Package Geometry/Pastemask Top")
		(15 "B.Paste" user "Package Geometry/Pastemask Bottom")
		(5 "F.SilkS" user "Ref Des/Silkscreen Top")
		(7 "B.SilkS" user "Ref Des/Silkscreen Bottom")
		(1 "F.Mask" user "Board Geometry/Soldermask Top")
		(3 "B.Mask" user "Board Geometry/Soldermask Bottom")
		(17 "Dwgs.User" user "User.Drawings")
		(19 "Cmts.User" user "User.Comments")
		(21 "Eco1.User" user "User.Eco1")
		(23 "Eco2.User" user "User.Eco2")
		(25 "Edge.Cuts" user "Board Geometry/Outline")
		(27 "Margin" user)
		(31 "F.CrtYd" user "Package Geometry/Place Bound Top")
		(29 "B.CrtYd" user "Package Geometry/Place Bound Bottom")
		(35 "F.Fab" user "Ref Des/Assembly Top")
		(33 "B.Fab" user "Ref Des/Assembly Bottom")
	)
	(footprint ""
		(layer "F.Cu")
		(at 277.0632 -79.6036 180)
		(property "Reference" "C6D2"
			(at 0 0 180)
			(layer "F.SilkS")
			(hide yes)
			(effects
				(font
					(size 1.27 1.27)
				)
			)
		)
		(property "Value" ""
			(at 0 0 180)
			(layer "F.Fab")
			(effects
				(font
					(size 1.27 1.27)
				)
			)
		)
		(duplicate_pad_numbers_are_jumpers no)
		(fp_poly
			(pts
				(xy -0.4953 -0.2032) (xy 0.4953 -0.2032) (xy 0.4953 1.6002) (xy -0.4953 1.6002)
			)
			(stroke
				(width 0)
				(type default)
			)
			(fill no)
			(layer "F.CrtYd")
		)
		(fp_line
			(start 0.4953 1.6002)
			(end -0.4953 1.6002)
			(stroke
				(width 0.1)
				(type default)
			)
			(layer "F.Fab")
		)
		(fp_line
			(start 0.4953 -0.2032)
			(end 0.4953 1.6002)
			(stroke
				(width 0.1)
				(type default)
			)
			(layer "F.Fab")
		)
		(fp_line
			(start -0.4953 1.6002)
			(end -0.4953 -0.2032)
			(stroke
				(width 0.1)
				(type default)
			)
			(layer "F.Fab")
		)
		(fp_line
			(start -0.4953 -0.2032)
			(end 0.4953 -0.2032)
			(stroke
				(width 0.1)
				(type default)
			)
			(layer "F.Fab")
		)
		(pad "1" smd rect
			(at 0 0 180)
			(size 0.762 0.889)
			(layers "F.Cu" "F.Mask" "F.Paste")
			(net "PVCCMCP_CPU0")
		)
		(pad "2" smd rect
			(at 0 1.397 180)
			(size 0.762 0.889)
			(layers "F.Cu" "F.Mask" "F.Paste")
			(net "GND")
		)
		(zone
			(layer "F.Cu")
			(hatch none 0.5)
			(connect_pads
				(clearance 0)
			)
			(min_thickness 0.25)
			(keepout
				(tracks not_allowed)
				(vias allowed)
				(pads allowed)
				(copperpour not_allowed)
				(footprints allowed)
			)
			(placement
				(enabled no)
				(sheetname "")
			)
			(fill
				(thermal_gap 0.5)
				(thermal_bridge_width 0.5)
				(island_removal_mode 0)
			)
			(polygon
				(pts
					(xy 277.4442 -80.0481) (xy 276.6822 -80.0481) (xy 276.6822 -80.5561) (xy 277.4442 -80.5561)
				)
			)
		)
	)
	(footprint ""
		(layer "F.Cu")
		(at 281.01036 -81.96072 90)
		(property "Reference" "R6D16"
			(at 0 0 90)
			(layer "F.SilkS")
			(hide yes)
			(effects
				(font
					(size 1.27 1.27)
				)
			)
		)
		(property "Value" ""
			(at 0 0 90)
			(layer "F.Fab")
			(effects
				(font
					(size 1.27 1.27)
				)
			)
		)
		(duplicate_pad_numbers_are_jumpers no)
		(fp_poly
			(pts
				(xy -0.2794 -0.1016) (xy 0.2794 -0.1016) (xy 0.2794 0.9906) (xy -0.2794 0.9906)
			)
			(stroke
				(width 0)
				(type default)
			)
			(fill no)
			(layer "F.CrtYd")
		)
		(fp_line
			(start 0.2794 -0.1016)
			(end -0.2794 -0.1016)
			(stroke
				(width 0.1)
				(type default)
			)
			(layer "F.Fab")
		)
		(fp_line
			(start -0.2794 -0.1016)
			(end -0.2794 0.9906)
			(stroke
				(width 0.1)
				(type default)
			)
			(layer "F.Fab")
		)
		(fp_line
			(start 0.2794 0.9906)
			(end 0.2794 -0.1016)
			(stroke
				(width 0.1)
				(type default)
			)
			(layer "F.Fab")
		)
		(fp_line
			(start -0.2794 0.9906)
			(end 0.2794 0.9906)
			(stroke
				(width 0.1)
				(type default)
			)
			(layer "F.Fab")
		)
		(pad "1" smd rect
			(at 0 0 90)
			(size 0.508 0.508)
			(layers "F.Cu" "F.Mask" "F.Paste")
			(net "FM_CPU_BMC_INIT")
		)
		(pad "2" smd rect
			(at 0 0.889 90)
			(size 0.508 0.508)
			(layers "F.Cu" "F.Mask" "F.Paste")
			(net "H_CPU0_BMCINIT")
		)
		(zone
			(layer "F.Cu")
			(hatch none 0.5)
			(connect_pads
				(clearance 0)
			)
			(min_thickness 0.25)
			(keepout
				(tracks allowed)
				(vias not_allowed)
				(pads allowed)
				(copperpour not_allowed)
				(footprints allowed)
			)
			(placement
				(enabled no)
				(sheetname "")
			)
			(fill
				(thermal_gap 0.5)
				(thermal_bridge_width 0.5)
				(island_removal_mode 0)
			)
			(polygon
				(pts
					(xy 281.26436 -81.70672) (xy 281.26436 -82.21472) (xy 281.64536 -82.21472) (xy 281.64536 -81.70672)
				)
			)
		)
		(zone
			(layer "F.Cu")
			(hatch none 0.5)
			(connect_pads
				(clearance 0)
			)
			(min_thickness 0.25)
			(keepout
				(tracks not_allowed)
				(vias allowed)
				(pads allowed)
				(copperpour not_allowed)
				(footprints allowed)
			)
			(placement
				(enabled no)
				(sheetname "")
			)
			(fill
				(thermal_gap 0.5)
				(thermal_bridge_width 0.5)
				(island_removal_mode 0)
			)
			(polygon
				(pts
					(xy 281.64536 -81.70672) (xy 281.64536 -82.21472) (xy 281.26436 -82.21472) (xy 281.26436 -81.70672)
				)
			)
		)
	)
	(footprint ""
		(layer "F.Cu")
		(at 354.805234 -129.3622)
		(property "Reference" "R7B17"
			(at 0 0 0)
			(layer "F.SilkS")
			(hide yes)
			(effects
				(font
					(size 1.27 1.27)
				)
			)
		)
		(property "Value" ""
			(at 0 0 0)
			(layer "F.Fab")
			(effects
				(font
					(size 1.27 1.27)
				)
			)
		)
		(duplicate_pad_numbers_are_jumpers no)
		(fp_poly
			(pts
				(xy -0.2794 -0.1016) (xy 0.2794 -0.1016) (xy 0.2794 0.9906) (xy -0.2794 0.9906)
			)
			(stroke
				(width 0)
				(type default)
			)
			(fill no)
			(layer "F.CrtYd")
		)
		(fp_line
			(start -0.2794 -0.1016)
			(end -0.2794 0.9906)
			(stroke
				(width 0.1)
				(type default)
			)
			(layer "F.Fab")
		)
		(fp_line
			(start -0.2794 0.9906)
			(end 0.2794 0.9906)
			(stroke
				(width 0.1)
				(type default)
			)
			(layer "F.Fab")
		)
		(fp_line
			(start 0.2794 -0.1016)
			(end -0.2794 -0.1016)
			(stroke
				(width 0.1)
				(type default)
			)
			(layer "F.Fab")
		)
		(fp_line
			(start 0.2794 0.9906)
			(end 0.2794 -0.1016)
			(stroke
				(width 0.1)
				(type default)
			)
			(layer "F.Fab")
		)
		(pad "1" smd rect
			(at 0 0)
			(size 0.508 0.508)
			(layers "F.Cu" "F.Mask" "F.Paste")
			(net "P3V3_STBY")
		)
		(pad "2" smd rect
			(at 0 0.889)
			(size 0.508 0.508)
			(layers "F.Cu" "F.Mask" "F.Paste")
			(net "PWRGD_PVPP_DEF_R")
		)
		(zone
			(layer "F.Cu")
			(hatch none 0.5)
			(connect_pads
				(clearance 0)
			)
			(min_thickness 0.25)
			(keepout
				(tracks allowed)
				(vias not_allowed)
				(pads allowed)
				(copperpour not_allowed)
				(footprints allowed)
			)
			(placement
				(enabled no)
				(sheetname "")
			)
			(fill
				(thermal_gap 0.5)
				(thermal_bridge_width 0.5)
				(island_removal_mode 0)
			)
			(polygon
				(pts
					(xy 354.551234 -129.1082) (xy 355.059234 -129.1082) (xy 355.059234 -128.7272) (xy 354.551234 -128.7272)
				)
			)
		)
		(zone
			(layer "F.Cu")
			(hatch none 0.5)
			(connect_pads
				(clearance 0)
			)
			(min_thickness 0.25)
			(keepout
				(tracks not_allowed)
				(vias allowed)
				(pads allowed)
				(copperpour not_allowed)
				(footprints allowed)
			)
			(placement
				(enabled no)
				(sheetname "")
			)
			(fill
				(thermal_gap 0.5)
				(thermal_bridge_width 0.5)
				(island_removal_mode 0)
			)
			(polygon
				(pts
					(xy 354.551234 -128.7272) (xy 355.059234 -128.7272) (xy 355.059234 -129.1082) (xy 354.551234 -129.1082)
				)
			)
		)
	)
)
